# S9S_MB_2U (Grand Teton) — schematic netlist excerpt (pin names and nets, part order shuffled) for the footprints in the layout excerpt that follows; sources: Cadence DE-HDL packaged netlist, KiCad conversion of 03242023_DA0F0TMBIJ0_F0T_Motherboard_J_brd_V01_OCP.brd

PR291  Q_RES  8.87K 1% EMPTY  pkg 0402LF  page 287 : A = PVCCIN_CPU1_LSET6 ; B = GND
R3726  Q_RES  2.2K 5% CHIP  pkg 0402LF  page 233 : A = P3V3_AUX ; B = SMB_LM75_0_3V3AUX_SDA

(kicad_pcb
	(version 20260206)
	(generator "pcbnew")
	(generator_version "10.0")
	(general
		(thickness 1.6)
		(legacy_teardrops no)
	)
	(paper "A4")
	(title_block
		(title "03242023_DA0F0TMBIJ0_F0T_Motherboard_J_brd_V01_OCP.brd")
		(comment 1 "Grand Teton / footprints 484-485 of 6105")
	)
	(layers
		(0 "F.Cu" signal "TOP")
		(4 "In1.Cu" signal "GND")
		(6 "In2.Cu" signal "IN1")
		(8 "In3.Cu" signal "GND1")
		(10 "In4.Cu" signal "IN2")
		(12 "In5.Cu" signal "GND2")
		(14 "In6.Cu" signal "IN3")
		(16 "In7.Cu" signal "GND3")
		(18 "In8.Cu" signal "VCC")
		(20 "In9.Cu" signal "VCC1")
		(22 "In10.Cu" signal "GND4")
		(24 "In11.Cu" signal "IN4")
		(26 "In12.Cu" signal "GND5")
		(28 "In13.Cu" signal "IN5")
		(30 "In14.Cu" signal "GND6")
		(32 "In15.Cu" signal "IN6")
		(34 "In16.Cu" signal "GND7")
		(2 "B.Cu" signal "BOTTOM")
		(9 "F.Adhes" user "F.Adhesive")
		(11 "B.Adhes" user "B.Adhesive")
		(13 "F.Paste" user "Package Geometry/Pastemask Top")
		(15 "B.Paste" user "Package Geometry/Pastemask Bottom")
		(5 "F.SilkS" user "Ref Des/Silkscreen Top")
		(7 "B.SilkS" user "Ref Des/Silkscreen Bottom")
		(1 "F.Mask" user "Board Geometry/Soldermask Top")
		(3 "B.Mask" user "Board Geometry/Soldermask Bottom")
		(17 "Dwgs.User" user "User.Drawings")
		(19 "Cmts.User" user "User.Comments")
		(21 "Eco1.User" user "User.Eco1")
		(23 "Eco2.User" user "User.Eco2")
		(25 "Edge.Cuts" user "Board Geometry/Outline")
		(27 "Margin" user)
		(31 "F.CrtYd" user "Package Geometry/Place Bound Top")
		(29 "B.CrtYd" user "Package Geometry/Place Bound Bottom")
		(35 "F.Fab" user "Ref Des/Assembly Top")
		(33 "B.Fab" user "Ref Des/Assembly Bottom")
	)
	(footprint ""
		(layer "F.Cu")
		(at 87.545926 -342.270334)
		(property "Reference" "PR291"
			(at 0 0 0)
			(layer "F.SilkS")
			(hide yes)
			(effects
				(font
					(size 1.27 1.27)
				)
			)
		)
		(property "Value" ""
			(at 0 0 0)
			(layer "F.Fab")
			(effects
				(font
					(size 1.27 1.27)
				)
			)
		)
		(duplicate_pad_numbers_are_jumpers no)
		(fp_line
			(start -0.7874 -0.4064)
			(end 0.7874 -0.4064)
			(stroke
				(width 0.1524)
				(type default)
			)
			(layer "F.SilkS")
		)
		(fp_line
			(start -0.7874 0.4064)
			(end -0.7874 -0.4064)
			(stroke
				(width 0.1524)
				(type default)
			)
			(layer "F.SilkS")
		)
		(fp_line
			(start 0.7874 -0.4064)
			(end 0.7874 0.4064)
			(stroke
				(width 0.1524)
				(type default)
			)
			(layer "F.SilkS")
		)
		(fp_line
			(start 0.7874 0.4064)
			(end -0.7874 0.4064)
			(stroke
				(width 0.1524)
				(type default)
			)
			(layer "F.SilkS")
		)
		(fp_line
			(start -0.67945 -0.305054)
			(end -0.12065 -0.305054)
			(stroke
				(width 0.1)
				(type default)
			)
			(layer "F.Fab")
		)
		(fp_line
			(start -0.67945 0.3048)
			(end -0.67945 -0.305054)
			(stroke
				(width 0.1)
				(type default)
			)
			(layer "F.Fab")
		)
		(fp_line
			(start -0.12065 -0.305054)
			(end -0.12065 -0.2794)
			(stroke
				(width 0.1)
				(type default)
			)
			(layer "F.Fab")
		)
		(fp_line
			(start -0.12065 -0.2794)
			(end 0.12065 -0.2794)
			(stroke
				(width 0.1)
				(type default)
			)
			(layer "F.Fab")
		)
		(fp_line
			(start -0.12065 0.2794)
			(end -0.12065 0.3048)
			(stroke
				(width 0.1)
				(type default)
			)
			(layer "F.Fab")
		)
		(fp_line
			(start -0.12065 0.3048)
			(end -0.67945 0.3048)
			(stroke
				(width 0.1)
				(type default)
			)
			(layer "F.Fab")
		)
		(fp_line
			(start 0.120396 0.2794)
			(end -0.12065 0.2794)
			(stroke
				(width 0.1)
				(type default)
			)
			(layer "F.Fab")
		)
		(fp_line
			(start 0.120396 0.3048)
			(end 0.120396 0.2794)
			(stroke
				(width 0.1)
				(type default)
			)
			(layer "F.Fab")
		)
		(fp_line
			(start 0.12065 -0.3048)
			(end 0.67945 -0.3048)
			(stroke
				(width 0.1)
				(type default)
			)
			(layer "F.Fab")
		)
		(fp_line
			(start 0.12065 -0.2794)
			(end 0.12065 -0.3048)
			(stroke
				(width 0.1)
				(type default)
			)
			(layer "F.Fab")
		)
		(fp_line
			(start 0.67945 -0.3048)
			(end 0.67945 0.3048)
			(stroke
				(width 0.1)
				(type default)
			)
			(layer "F.Fab")
		)
		(fp_line
			(start 0.67945 0.3048)
			(end 0.120396 0.3048)
			(stroke
				(width 0.1)
				(type default)
			)
			(layer "F.Fab")
		)
		(pad "1" smd circle
			(at -0.40005 0)
			(size 0 0)
			(layers "F.Cu" "F.Mask" "F.Paste")
			(net "PVCCIN_CPU1_LSET6")
		)
		(pad "2" smd circle
			(at 0.40005 0)
			(size 0 0)
			(layers "F.Cu" "F.Mask" "F.Paste")
			(net "GND")
		)
	)
	(footprint ""
		(layer "F.Cu")
		(at 51.593496 -112.33277)
		(property "Reference" "R3726"
			(at 0 0 0)
			(layer "F.SilkS")
			(hide yes)
			(effects
				(font
					(size 1.27 1.27)
				)
			)
		)
		(property "Value" ""
			(at 0 0 0)
			(layer "F.Fab")
			(effects
				(font
					(size 1.27 1.27)
				)
			)
		)
		(duplicate_pad_numbers_are_jumpers no)
		(fp_line
			(start -0.7874 -0.4064)
			(end 0.7874 -0.4064)
			(stroke
				(width 0.1524)
				(type default)
			)
			(layer "F.SilkS")
		)
		(fp_line
			(start -0.7874 0.4064)
			(end -0.7874 -0.4064)
			(stroke
				(width 0.1524)
				(type default)
			)
			(layer "F.SilkS")
		)
		(fp_line
			(start 0.7874 -0.4064)
			(end 0.7874 0.4064)
			(stroke
				(width 0.1524)
				(type default)
			)
			(layer "F.SilkS")
		)
		(fp_line
			(start 0.7874 0.4064)
			(end -0.7874 0.4064)
			(stroke
				(width 0.1524)
				(type default)
			)
			(layer "F.SilkS")
		)
		(fp_line
			(start -0.67945 -0.305054)
			(end -0.12065 -0.305054)
			(stroke
				(width 0.1)
				(type default)
			)
			(layer "F.Fab")
		)
		(fp_line
			(start -0.67945 0.3048)
			(end -0.67945 -0.305054)
			(stroke
				(width 0.1)
				(type default)
			)
			(layer "F.Fab")
		)
		(fp_line
			(start -0.12065 -0.305054)
			(end -0.12065 -0.2794)
			(stroke
				(width 0.1)
				(type default)
			)
			(layer "F.Fab")
		)
		(fp_line
			(start -0.12065 -0.2794)
			(end 0.12065 -0.2794)
			(stroke
				(width 0.1)
				(type default)
			)
			(layer "F.Fab")
		)
		(fp_line
			(start -0.12065 0.2794)
			(end -0.12065 0.3048)
			(stroke
				(width 0.1)
				(type default)
			)
			(layer "F.Fab")
		)
		(fp_line
			(start -0.12065 0.3048)
			(end -0.67945 0.3048)
			(stroke
				(width 0.1)
				(type default)
			)
			(layer "F.Fab")
		)
		(fp_line
			(start 0.120396 0.2794)
			(end -0.12065 0.2794)
			(stroke
				(width 0.1)
				(type default)
			)
			(layer "F.Fab")
		)
		(fp_line
			(start 0.120396 0.3048)
			(end 0.120396 0.2794)
			(stroke
				(width 0.1)
				(type default)
			)
			(layer "F.Fab")
		)
		(fp_line
			(start 0.12065 -0.3048)
			(end 0.67945 -0.3048)
			(stroke
				(width 0.1)
				(type default)
			)
			(layer "F.Fab")
		)
		(fp_line
			(start 0.12065 -0.2794)
			(end 0.12065 -0.3048)
			(stroke
				(width 0.1)
				(type default)
			)
			(layer "F.Fab")
		)
		(fp_line
			(start 0.67945 -0.3048)
			(end 0.67945 0.3048)
			(stroke
				(width 0.1)
				(type default)
			)
			(layer "F.Fab")
		)
		(fp_line
			(start 0.67945 0.3048)
			(end 0.120396 0.3048)
			(stroke
				(width 0.1)
				(type default)
			)
			(layer "F.Fab")
		)
		(pad "1" smd circle
			(at -0.40005 0)
			(size 0 0)
			(layers "F.Cu" "F.Mask" "F.Paste")
			(net "P3V3_AUX")
		)
		(pad "2" smd circle
			(at 0.40005 0)
			(size 0 0)
			(layers "F.Cu" "F.Mask" "F.Paste")
			(net "SMB_LM75_0_3V3AUX_SDA")
		)
	)
)
